G04 ================== begin FILE IDENTIFICATION RECORD ==================*
G04 Layout Name:  17301-sa.brd*
G04 Film Name:    BMASK*
G04 File Format:  Gerber RS274X*
G04 File Origin:  Cadence Allegro 16.6-2015-S079*
G04 Origin Date:  Thu Jun 22 17:49:46 2017*
G04 *
G04 Layer:  VIA CLASS/SOLDERMASK_BOTTOM*
G04 Layer:  PIN/SOLDERMASK_BOTTOM*
G04 Layer:  PACKAGE GEOMETRY/SOLDERMASK_BOTTOM*
G04 Layer:  DRAWING FORMAT/LAYER_SOLDER_B*
G04 Layer:  BOARD GEOMETRY/SOLDERMASK_BOTTOM*
G04 Layer:  DRAWING FORMAT/LAYER_PCB_STORY*
G04 *
G04 Offset:    (0.00 0.00)*
G04 Mirror:    No*
G04 Mode:      Positive*
G04 Rotation:  0*
G04 FullContactRelief:  No*
G04 UndefLineWidth:     6.00*
G04 ================== end FILE IDENTIFICATION RECORD ====================*
%FSLAX35Y35*MOIN*%
%IR0*IPPOS*OFA0.00000B0.00000*MIA0B0*SFA1.00000B1.00000*%
%AMMACRO23*
4,1,40,.011,.007,
.011,-.007,
.010939,-.007695,
.010759,-.008368,
.010464,-.009,
.010064,-.009571,
.009571,-.010064,
.009,-.010464,
.008368,-.010759,
.007695,-.010939,
.007,-.011,
-.007,-.011,
-.007695,-.010939,
-.008368,-.010759,
-.009,-.010464,
-.009571,-.010064,
-.010064,-.009571,
-.010464,-.009,
-.010759,-.008368,
-.010939,-.007695,
-.011,-.007,
-.011,.007,
-.010939,.007695,
-.010759,.008368,
-.010464,.009,
-.010064,.009571,
-.009571,.010064,
-.009,.010464,
-.008368,.010759,
-.007695,.010939,
-.007,.011,
.007,.011,
.007695,.010939,
.008368,.010759,
.009,.010464,
.009571,.010064,
.010064,.009571,
.010464,.009,
.010759,.008368,
.010939,.007695,
.011,.007,
0.0*
%
%ADD23MACRO23*%
%AMMACRO38*
4,1,40,.013,-.017,
-.013,-.017,
-.013695,-.016939,
-.014368,-.016759,
-.015,-.016464,
-.015571,-.016064,
-.016064,-.015571,
-.016464,-.015,
-.016759,-.014368,
-.016939,-.013695,
-.017,-.013,
-.017,.013,
-.016939,.013695,
-.016759,.014368,
-.016464,.015,
-.016064,.015571,
-.015571,.016064,
-.015,.016464,
-.014368,.016759,
-.013695,.016939,
-.013,.017,
.013,.017,
.013695,.016939,
.014368,.016759,
.015,.016464,
.015571,.016064,
.016064,.015571,
.016464,.015,
.016759,.014368,
.016939,.013695,
.017,.013,
.017,-.013,
.016939,-.013695,
.016759,-.014368,
.016464,-.015,
.016064,-.015571,
.015571,-.016064,
.015,-.016464,
.014368,-.016759,
.013695,-.016939,
.013,-.017,
0.0*
%
%ADD38MACRO38*%
%ADD43C,.05*%
%ADD36C,.014*%
%ADD16C,.034*%
%ADD44C,.071*%
%ADD19C,.053*%
%ADD12C,.08*%
%ADD17C,.028*%
%ADD41C,.048*%
%ADD14C,.093*%
%ADD10C,.086*%
%AMMACRO28*
4,1,44,.023,.00387,
.022901,.005261,
.022562,.006614,
.021993,.007887,
.021211,.009042,
.020241,.010044,
.019112,.010863,
.017857,.011472,
.016516,.011855,
.015129,.011999,
.015,.012,
-.015,.012,
-.016389,.011878,
-.017737,.011517,
-.019001,.010928,
-.020143,.010128,
-.021129,.009142,
-.021929,.007999,
-.022519,.006735,
-.022879,.005388,
-.023001,.003999,
-.023,.00387,
-.023,-.00387,
-.022901,-.005261,
-.022562,-.006614,
-.021993,-.007887,
-.021211,-.009042,
-.020241,-.010044,
-.019112,-.010863,
-.017857,-.011472,
-.016516,-.011855,
-.015129,-.011999,
-.015,-.012,
.015,-.012,
.016389,-.011878,
.017737,-.011517,
.019001,-.010928,
.020143,-.010128,
.021129,-.009142,
.021929,-.007999,
.022519,-.006735,
.022879,-.005388,
.023001,-.003999,
.023,-.00387,
.023,.00387,
0.0*
%
%ADD28MACRO28*%
%AMMACRO42*
4,1,40,-.012,-.008,
-.012,.008,
-.011939,.008695,
-.011759,.009368,
-.011464,.01,
-.011064,.010571,
-.010571,.011064,
-.01,.011464,
-.009368,.011759,
-.008695,.011939,
-.008,.012,
.008,.012,
.008695,.011939,
.009368,.011759,
.01,.011464,
.010571,.011064,
.011064,.010571,
.011464,.01,
.011759,.009368,
.011939,.008695,
.012,.008,
.012,-.008,
.011939,-.008695,
.011759,-.009368,
.011464,-.01,
.011064,-.010571,
.010571,-.011064,
.01,-.011464,
.009368,-.011759,
.008695,-.011939,
.008,-.012,
-.008,-.012,
-.008695,-.011939,
-.009368,-.011759,
-.01,-.011464,
-.010571,-.011064,
-.011064,-.010571,
-.011464,-.01,
-.011759,-.009368,
-.011939,-.008695,
-.012,-.008,
0.0*
%
%ADD42MACRO42*%
%AMMACRO26*
4,1,40,-.013,.017,
.013,.017,
.013695,.016939,
.014368,.016759,
.015,.016464,
.015571,.016064,
.016064,.015571,
.016464,.015,
.016759,.014368,
.016939,.013695,
.017,.013,
.017,-.013,
.016939,-.013695,
.016759,-.014368,
.016464,-.015,
.016064,-.015571,
.015571,-.016064,
.015,-.016464,
.014368,-.016759,
.013695,-.016939,
.013,-.017,
-.013,-.017,
-.013695,-.016939,
-.014368,-.016759,
-.015,-.016464,
-.015571,-.016064,
-.016064,-.015571,
-.016464,-.015,
-.016759,-.014368,
-.016939,-.013695,
-.017,-.013,
-.017,.013,
-.016939,.013695,
-.016759,.014368,
-.016464,.015,
-.016064,.015571,
-.015571,.016064,
-.015,.016464,
-.014368,.016759,
-.013695,.016939,
-.013,.017,
0.0*
%
%ADD26MACRO26*%
%AMMACRO40*
4,1,40,-.012,-.008,
-.012,.008,
-.011939,.008695,
-.011759,.009368,
-.011464,.01,
-.011064,.010571,
-.010571,.011064,
-.01,.011464,
-.009368,.011759,
-.008695,.011939,
-.008,.012,
.008,.012,
.008695,.011939,
.009368,.011759,
.01,.011464,
.010571,.011064,
.011064,.010571,
.011464,.01,
.011759,.009368,
.011939,.008695,
.012,.008,
.012,-.008,
.011939,-.008695,
.011759,-.009368,
.011464,-.01,
.011064,-.010571,
.010571,-.011064,
.01,-.011464,
.009368,-.011759,
.008695,-.011939,
.008,-.012,
-.008,-.012,
-.008695,-.011939,
-.009368,-.011759,
-.01,-.011464,
-.010571,-.011064,
-.011064,-.010571,
-.011464,-.01,
-.011759,-.009368,
-.011939,-.008695,
-.012,-.008,
0.0*
%
%ADD40MACRO40*%
%AMMACRO27*
4,1,40,-.013,.017,
.013,.017,
.013695,.016939,
.014368,.016759,
.015,.016464,
.015571,.016064,
.016064,.015571,
.016464,.015,
.016759,.014368,
.016939,.013695,
.017,.013,
.017,-.013,
.016939,-.013695,
.016759,-.014368,
.016464,-.015,
.016064,-.015571,
.015571,-.016064,
.015,-.016464,
.014368,-.016759,
.013695,-.016939,
.013,-.017,
-.013,-.017,
-.013695,-.016939,
-.014368,-.016759,
-.015,-.016464,
-.015571,-.016064,
-.016064,-.015571,
-.016464,-.015,
-.016759,-.014368,
-.016939,-.013695,
-.017,-.013,
-.017,.013,
-.016939,.013695,
-.016759,.014368,
-.016464,.015,
-.016064,.015571,
-.015571,.016064,
-.015,.016464,
-.014368,.016759,
-.013695,.016939,
-.013,.017,
0.0*
%
%ADD27MACRO27*%
%ADD39R,.04X.022*%
%ADD18O,.024X.032*%
%ADD35R,.016X.04*%
%ADD13R,.071X.032*%
%ADD15R,.063X.024*%
%ADD31R,.05X.065*%
%ADD29R,.047X.014*%
%ADD21R,.065X.025*%
%ADD45R,.045X.055*%
%ADD34R,.016X.048*%
%ADD11C,.237*%
%ADD30O,.086X.048*%
%AMMACRO20*
4,1,40,-.007,.0225,
-.008389,.022378,
-.009736,.022018,
-.011,.021428,
-.012142,.020628,
-.013128,.019642,
-.013928,.0185,
-.014518,.017236,
-.014878,.015889,
-.015,.0145,
-.015,-.0145,
-.014878,-.015889,
-.014518,-.017236,
-.013928,-.0185,
-.013128,-.019642,
-.012142,-.020628,
-.011,-.021428,
-.009736,-.022018,
-.008389,-.022378,
-.007,-.0225,
.007,-.0225,
.008389,-.022378,
.009736,-.022018,
.011,-.021428,
.012142,-.020628,
.013128,-.019642,
.013928,-.0185,
.014518,-.017236,
.014878,-.015889,
.015,-.0145,
.015,.0145,
.014878,.015889,
.014518,.017236,
.013928,.0185,
.013128,.019642,
.012142,.020628,
.011,.021428,
.009736,.022018,
.008389,.022378,
.007,.0225,
-.007,.0225,
0.0*
%
%ADD20MACRO20*%
%AMMACRO33*
4,1,40,.012,.008,
.012,-.008,
.011939,-.008695,
.011759,-.009368,
.011464,-.01,
.011064,-.010571,
.010571,-.011064,
.01,-.011464,
.009368,-.011759,
.008695,-.011939,
.008,-.012,
-.008,-.012,
-.008695,-.011939,
-.009368,-.011759,
-.01,-.011464,
-.010571,-.011064,
-.011064,-.010571,
-.011464,-.01,
-.011759,-.009368,
-.011939,-.008695,
-.012,-.008,
-.012,.008,
-.011939,.008695,
-.011759,.009368,
-.011464,.01,
-.011064,.010571,
-.010571,.011064,
-.01,.011464,
-.009368,.011759,
-.008695,.011939,
-.008,.012,
.008,.012,
.008695,.011939,
.009368,.011759,
.01,.011464,
.010571,.011064,
.011064,.010571,
.011464,.01,
.011759,.009368,
.011939,.008695,
.012,.008,
0.0*
%
%ADD33MACRO33*%
%AMMACRO25*
4,1,40,.008,-.012,
-.008,-.012,
-.008695,-.011939,
-.009368,-.011759,
-.01,-.011464,
-.010571,-.011064,
-.011064,-.010571,
-.011464,-.01,
-.011759,-.009368,
-.011939,-.008695,
-.012,-.008,
-.012,.008,
-.011939,.008695,
-.011759,.009368,
-.011464,.01,
-.011064,.010571,
-.010571,.011064,
-.01,.011464,
-.009368,.011759,
-.008695,.011939,
-.008,.012,
.008,.012,
.008695,.011939,
.009368,.011759,
.01,.011464,
.010571,.011064,
.011064,.010571,
.011464,.01,
.011759,.009368,
.011939,.008695,
.012,.008,
.012,-.008,
.011939,-.008695,
.011759,-.009368,
.011464,-.01,
.011064,-.010571,
.010571,-.011064,
.01,-.011464,
.009368,-.011759,
.008695,-.011939,
.008,-.012,
0.0*
%
%ADD25MACRO25*%
%AMMACRO22*
4,1,40,.011,.007,
.011,-.007,
.010939,-.007695,
.010759,-.008368,
.010464,-.009,
.010064,-.009571,
.009571,-.010064,
.009,-.010464,
.008368,-.010759,
.007695,-.010939,
.007,-.011,
-.007,-.011,
-.007695,-.010939,
-.008368,-.010759,
-.009,-.010464,
-.009571,-.010064,
-.010064,-.009571,
-.010464,-.009,
-.010759,-.008368,
-.010939,-.007695,
-.011,-.007,
-.011,.007,
-.010939,.007695,
-.010759,.008368,
-.010464,.009,
-.010064,.009571,
-.009571,.010064,
-.009,.010464,
-.008368,.010759,
-.007695,.010939,
-.007,.011,
.007,.011,
.007695,.010939,
.008368,.010759,
.009,.010464,
.009571,.010064,
.010064,.009571,
.010464,.009,
.010759,.008368,
.010939,.007695,
.011,.007,
0.0*
%
%ADD22MACRO22*%
%AMMACRO37*
4,1,40,.013,-.017,
-.013,-.017,
-.013695,-.016939,
-.014368,-.016759,
-.015,-.016464,
-.015571,-.016064,
-.016064,-.015571,
-.016464,-.015,
-.016759,-.014368,
-.016939,-.013695,
-.017,-.013,
-.017,.013,
-.016939,.013695,
-.016759,.014368,
-.016464,.015,
-.016064,.015571,
-.015571,.016064,
-.015,.016464,
-.014368,.016759,
-.013695,.016939,
-.013,.017,
.013,.017,
.013695,.016939,
.014368,.016759,
.015,.016464,
.015571,.016064,
.016064,.015571,
.016464,.015,
.016759,.014368,
.016939,.013695,
.017,.013,
.017,-.013,
.016939,-.013695,
.016759,-.014368,
.016464,-.015,
.016064,-.015571,
.015571,-.016064,
.015,-.016464,
.014368,-.016759,
.013695,-.016939,
.013,-.017,
0.0*
%
%ADD37MACRO37*%
%AMMACRO32*
4,1,40,.012,.008,
.012,-.008,
.011939,-.008695,
.011759,-.009368,
.011464,-.01,
.011064,-.010571,
.010571,-.011064,
.01,-.011464,
.009368,-.011759,
.008695,-.011939,
.008,-.012,
-.008,-.012,
-.008695,-.011939,
-.009368,-.011759,
-.01,-.011464,
-.010571,-.011064,
-.011064,-.010571,
-.011464,-.01,
-.011759,-.009368,
-.011939,-.008695,
-.012,-.008,
-.012,.008,
-.011939,.008695,
-.011759,.009368,
-.011464,.01,
-.011064,.010571,
-.010571,.011064,
-.01,.011464,
-.009368,.011759,
-.008695,.011939,
-.008,.012,
.008,.012,
.008695,.011939,
.009368,.011759,
.01,.011464,
.010571,.011064,
.011064,.010571,
.011464,.01,
.011759,.009368,
.011939,.008695,
.012,.008,
0.0*
%
%ADD32MACRO32*%
%AMMACRO24*
4,1,40,.008,-.012,
-.008,-.012,
-.008695,-.011939,
-.009368,-.011759,
-.01,-.011464,
-.010571,-.011064,
-.011064,-.010571,
-.011464,-.01,
-.011759,-.009368,
-.011939,-.008695,
-.012,-.008,
-.012,.008,
-.011939,.008695,
-.011759,.009368,
-.011464,.01,
-.011064,.010571,
-.010571,.011064,
-.01,.011464,
-.009368,.011759,
-.008695,.011939,
-.008,.012,
.008,.012,
.008695,.011939,
.009368,.011759,
.01,.011464,
.010571,.011064,
.011064,.010571,
.011464,.01,
.011759,.009368,
.011939,.008695,
.012,.008,
.012,-.008,
.011939,-.008695,
.011759,-.009368,
.011464,-.01,
.011064,-.010571,
.010571,-.011064,
.01,-.011464,
.009368,-.011759,
.008695,-.011939,
.008,-.012,
0.0*
%
%ADD24MACRO24*%
%ADD46C,.02*%
%ADD47C,.006*%
G75*
%LPD*%
G75*
G54D10*
X-14755Y415558D03*
X-12454Y45507D03*
X17715Y44095D03*
X29461Y718854D03*
X141466Y655356D03*
X395935Y76695D03*
X508569Y15093D03*
X525590Y240944D03*
X552795Y40157D03*
X554126Y315939D03*
Y685624D03*
G54D20*
X272221Y22319D03*
X268346Y29819D03*
X276096D03*
X319229Y172944D03*
X315354Y180444D03*
X323104D03*
G54D11*
X15748Y15827D03*
Y67008D03*
X303150Y13780D03*
Y242913D03*
X551181Y13780D03*
Y242913D03*
G54D30*
X295472Y65571D03*
Y108287D03*
X330590Y65571D03*
Y108287D03*
G54D21*
X267500Y52500D03*
Y47500D03*
Y42500D03*
Y37500D03*
X287500D03*
Y42500D03*
Y47500D03*
Y52500D03*
X309000Y149500D03*
Y164500D03*
Y159500D03*
Y154500D03*
X309131Y193554D03*
Y188554D03*
Y203554D03*
Y198554D03*
X338631Y52054D03*
Y47054D03*
Y42054D03*
Y37054D03*
X329000Y149500D03*
Y154500D03*
Y159500D03*
Y164500D03*
X329131Y188554D03*
Y193554D03*
Y198554D03*
Y203554D03*
X358631Y37054D03*
Y42054D03*
Y47054D03*
Y52054D03*
G54D12*
X20847Y701602D03*
X32739Y30456D03*
X514356Y57612D03*
G54D22*
X285083Y26528D03*
X332000Y176300D03*
G54D31*
X289800Y150000D03*
X300800D03*
X289800Y158700D03*
X300800D03*
G54D13*
X44685Y19685D03*
Y85039D03*
G54D40*
X318743Y50919D03*
X485348Y106794D03*
G54D32*
X296700Y164800D03*
X519597Y106778D03*
G54D14*
X68112Y15039D03*
Y59528D03*
X233462Y15039D03*
Y59528D03*
X359156Y142992D03*
Y208740D03*
X524506Y142992D03*
Y208740D03*
G54D41*
X312657Y66142D03*
Y107716D03*
G54D23*
X285083Y29928D03*
X332000Y179700D03*
G54D24*
X281083Y26428D03*
X328034Y176234D03*
G54D33*
X293100Y164800D03*
X515997Y106778D03*
G54D15*
X54724Y24803D03*
Y28740D03*
Y32677D03*
Y36614D03*
Y40551D03*
Y44488D03*
Y48425D03*
Y52362D03*
Y56299D03*
Y60236D03*
Y64173D03*
Y68110D03*
Y72047D03*
Y75984D03*
Y79921D03*
G54D42*
X322343Y50919D03*
X488948Y106794D03*
G54D25*
X281083Y30028D03*
X328034Y179834D03*
G54D34*
X306460Y32950D03*
X301340D03*
Y39450D03*
X303900D03*
X306460D03*
X317440Y213250D03*
Y219750D03*
X320000D03*
X322560Y213250D03*
Y219750D03*
G54D16*
X93287Y10039D03*
X88287D03*
X93287Y54528D03*
X88287D03*
X118287Y10039D03*
X113287D03*
X108287D03*
X103287D03*
X98287D03*
X118287Y54528D03*
X113287D03*
X108287D03*
X103287D03*
X98287D03*
X163287Y10039D03*
X158287D03*
X153287D03*
X148287D03*
X143287D03*
X163287Y54528D03*
X158287D03*
X153287D03*
X148287D03*
X143287D03*
X183287Y10039D03*
X178287D03*
X173287D03*
X168287D03*
X183287Y54528D03*
X178287D03*
X173287D03*
X168287D03*
X208287Y10039D03*
X203287D03*
X198287D03*
X193287D03*
X188287D03*
X208287Y54528D03*
X203287D03*
X198287D03*
X193287D03*
X188287D03*
X213287Y10039D03*
Y54528D03*
X389331Y137992D03*
X384331D03*
X379331D03*
X389331Y203740D03*
X384331D03*
X379331D03*
X409331Y137992D03*
X404331D03*
X399331D03*
X394331D03*
X409331Y203740D03*
X404331D03*
X399331D03*
X394331D03*
X434331Y137992D03*
Y203740D03*
X459331Y137992D03*
X454331D03*
X449331D03*
X444331D03*
X439331D03*
X459331Y203740D03*
X454331D03*
X449331D03*
X444331D03*
X439331D03*
X479331Y137992D03*
X474331D03*
X469331D03*
X464331D03*
X479331Y203740D03*
X474331D03*
X469331D03*
X464331D03*
X504331Y137992D03*
X499331D03*
X494331D03*
X489331D03*
X484331D03*
X504331Y203740D03*
X499331D03*
X494331D03*
X489331D03*
X484331D03*
G54D43*
X473149Y79094D03*
X532205D03*
G54D35*
X318960Y33000D03*
X316400D03*
X313840D03*
Y40400D03*
X316400D03*
X318960D03*
X306940Y140700D03*
X309500D03*
X312060D03*
Y133300D03*
X309500D03*
X306940D03*
X337440Y27700D03*
X340000D03*
X342560D03*
Y20300D03*
X340000D03*
X337440D03*
G54D26*
X293329Y58557D03*
G54D17*
X75100Y36700D03*
X74635Y29153D03*
X261939Y10864D03*
X261403Y18848D03*
X292129Y215485D03*
X288498Y207172D03*
X328196Y32237D03*
X337494Y177470D03*
X331841Y233317D03*
X470551Y112318D03*
X459514Y113175D03*
X506868Y166599D03*
X547629Y215319D03*
X549807Y89951D03*
G54D44*
X484960Y86811D03*
X496771D03*
X508583D03*
X520394D03*
G54D45*
X483520Y101104D03*
X491120D03*
X521558Y101034D03*
X513958D03*
G54D18*
X140237Y23464D03*
X137087D03*
X133937D03*
X130787D03*
X127637D03*
X124487D03*
X121337D03*
X140237Y67953D03*
X137087D03*
X133937D03*
X130787D03*
X127637D03*
X124487D03*
X121337D03*
X412381Y151417D03*
Y217165D03*
X431281Y151417D03*
X428131D03*
X424981D03*
X421831D03*
X418681D03*
X415531D03*
X431281Y217165D03*
X428131D03*
X424981D03*
X421831D03*
X418681D03*
X415531D03*
G54D27*
X287729Y58557D03*
G54D36*
X322100Y26600D03*
X309250Y127439D03*
X322042Y147196D03*
X310500Y184328D03*
X340000Y14667D03*
X351040Y34753D03*
X358900Y23928D03*
G54D46*
G01X-139981Y-146685D02*
G02I-12000J0D01*
G01X-145131D02*
G02I-6850J0D01*
G01X-135981D02*
X-167981D01*
G01X-135981Y-162685D02*
Y-242685D01*
G01D02*
X971619D01*
G01X-135981Y-198185D02*
X971619D01*
G01X-151981Y-162685D02*
Y-130685D01*
G01X-135981Y-162685D02*
X971619D01*
G01X184119D02*
Y-242685D01*
G01X321619Y-162685D02*
Y-242685D01*
G01X436619Y-162685D02*
Y-242685D01*
G01X604119Y-162685D02*
Y-242685D01*
G01X774119Y-162685D02*
Y-242685D01*
G01X971619Y-162685D02*
Y-242685D01*
G01X999619Y-146685D02*
G02I-12000J0D01*
G01X1003619D02*
X971619D01*
G01X994469D02*
G02I-6850J0D01*
G01X987619Y-162685D02*
Y-130685D01*
G54D37*
X307400Y46300D03*
G54D28*
X300444Y54732D03*
X307544Y57292D03*
Y52172D03*
G54D19*
X225097Y15039D03*
Y59528D03*
X516141Y142992D03*
Y208740D03*
G54D47*
G01X-116181Y-215185D02*
Y-232685D01*
G01X-121203Y-215185D02*
X-111159D01*
G01X-103048Y-232685D02*
Y-215185D01*
X-97808D01*
X-96061Y-216060D01*
X-94751Y-218102D01*
X-94314Y-220435D01*
X-94751Y-222768D01*
X-95843Y-224518D01*
X-97808Y-225394D01*
X-103048D01*
G01X-58878Y-216644D02*
X-60188Y-215768D01*
X-61716Y-215185D01*
X-63463D01*
X-65428Y-216060D01*
X-66956Y-217518D01*
X-68048Y-219269D01*
X-68921Y-222185D01*
X-69140Y-224810D01*
X-68703Y-227435D01*
X-68048Y-229185D01*
X-66738Y-230935D01*
X-65209Y-232102D01*
X-63681Y-232685D01*
X-62153D01*
X-60624Y-232102D01*
X-59314Y-231227D01*
X-58222Y-230061D01*
G01X-49893Y-232685D02*
Y-215185D01*
G01Y-223643D02*
X-48801Y-222185D01*
X-47709Y-221310D01*
X-45963Y-221019D01*
X-44653Y-221310D01*
X-43124Y-222477D01*
X-42469Y-224227D01*
Y-232685D01*
G01X-24751D02*
Y-221019D01*
G01Y-223060D02*
X-25624Y-221894D01*
X-26935Y-221310D01*
X-28463Y-221019D01*
X-29991Y-221602D01*
X-31301Y-222768D01*
X-32175Y-224518D01*
X-32611Y-226852D01*
X-32175Y-229185D01*
X-31301Y-230935D01*
X-29991Y-232102D01*
X-28463Y-232685D01*
X-26935Y-232393D01*
X-25624Y-231519D01*
X-24751Y-230352D01*
G01X-14893Y-232685D02*
Y-221019D01*
G01Y-223935D02*
X-14019Y-222477D01*
X-12709Y-221310D01*
X-10963Y-221019D01*
X-9435Y-221310D01*
X-8124Y-222477D01*
X-7469Y-224518D01*
Y-232685D01*
G01X2607D02*
Y-221019D01*
G01Y-223935D02*
X3481Y-222477D01*
X4791Y-221310D01*
X6537Y-221019D01*
X8065Y-221310D01*
X9376Y-222477D01*
X10031Y-224518D01*
Y-232685D01*
G01X20544Y-224810D02*
X27531D01*
X26876Y-222768D01*
X25784Y-221602D01*
X24256Y-221019D01*
X22727Y-221310D01*
X21417Y-222185D01*
X20544Y-224227D01*
X20107Y-225977D01*
Y-227727D01*
X20544Y-229477D01*
X21636Y-231227D01*
X22946Y-232393D01*
X24474Y-232685D01*
X26002Y-232102D01*
X27531Y-230352D01*
G01X41319Y-232685D02*
Y-215185D01*
G01X71734Y-232685D02*
Y-215185D01*
G01X80904D02*
Y-232685D01*
G01Y-223935D02*
X71734D01*
G01X89016Y-232685D02*
Y-215185D01*
X93382D01*
X95129Y-216060D01*
X96439Y-217227D01*
X97531Y-218976D01*
X98404Y-221019D01*
X98622Y-223935D01*
X98404Y-226852D01*
X97531Y-228894D01*
X96439Y-230644D01*
X95129Y-231810D01*
X93382Y-232685D01*
X89016D01*
G01X106516D02*
Y-215185D01*
X110882D01*
X112629Y-216060D01*
X113939Y-217227D01*
X115031Y-218976D01*
X115904Y-221019D01*
X116122Y-223935D01*
X115904Y-226852D01*
X115031Y-228894D01*
X113939Y-230644D01*
X112629Y-231810D01*
X110882Y-232685D01*
X106516D01*
G01X148065Y-223352D02*
X148939Y-222477D01*
X149594Y-221019D01*
X150031Y-218976D01*
X149594Y-217227D01*
X148721Y-216060D01*
X147192Y-215185D01*
X141297D01*
Y-232685D01*
X148502D01*
X150031Y-231519D01*
X150904Y-229768D01*
X151341Y-227727D01*
X150904Y-225685D01*
X149594Y-223935D01*
X148065Y-223352D01*
X141297D01*
G01X159452Y-232685D02*
Y-215185D01*
X164692D01*
X166439Y-216060D01*
X167749Y-218102D01*
X168186Y-220435D01*
X167749Y-222768D01*
X166657Y-224518D01*
X164692Y-225394D01*
X159452D01*
G01X-16858Y-187685D02*
Y-170185D01*
X-11181Y-184768D01*
X-5504Y-170185D01*
Y-187685D01*
G01X6319D02*
X5009Y-187393D01*
X3699Y-186227D01*
X2825Y-184185D01*
X2389Y-181852D01*
X2825Y-179518D01*
X3699Y-177477D01*
X5009Y-176310D01*
X6319Y-176019D01*
X7629Y-176310D01*
X8939Y-177477D01*
X9812Y-179518D01*
X10031Y-181852D01*
X9812Y-184185D01*
X8939Y-186227D01*
X7629Y-187393D01*
X6319Y-187685D01*
G01X27749Y-170185D02*
Y-187685D01*
G01Y-185061D02*
X26876Y-186519D01*
X25565Y-187393D01*
X24037Y-187685D01*
X22291Y-187102D01*
X20981Y-185644D01*
X20107Y-183894D01*
X19889Y-181852D01*
X20107Y-179810D01*
X20981Y-178060D01*
X22291Y-176602D01*
X24037Y-176019D01*
X25565Y-176310D01*
X26657Y-176894D01*
X27749Y-178060D01*
G01X38044Y-179810D02*
X45031D01*
X44376Y-177768D01*
X43284Y-176602D01*
X41756Y-176019D01*
X40227Y-176310D01*
X38917Y-177185D01*
X38044Y-179227D01*
X37607Y-180977D01*
Y-182727D01*
X38044Y-184477D01*
X39136Y-186227D01*
X40446Y-187393D01*
X41974Y-187685D01*
X43502Y-187102D01*
X45031Y-185352D01*
G01X58819Y-187685D02*
Y-170185D01*
G01X204702Y-187685D02*
Y-170185D01*
X209942D01*
X211689Y-171060D01*
X212999Y-173102D01*
X213436Y-175435D01*
X212999Y-177768D01*
X211907Y-179518D01*
X209942Y-180394D01*
X204702D01*
G01X231372Y-171644D02*
X230062Y-170768D01*
X228534Y-170185D01*
X226787D01*
X224822Y-171060D01*
X223294Y-172518D01*
X222202Y-174269D01*
X221329Y-177185D01*
X221110Y-179810D01*
X221547Y-182435D01*
X222202Y-184185D01*
X223512Y-185935D01*
X225041Y-187102D01*
X226569Y-187685D01*
X228097D01*
X229626Y-187102D01*
X230936Y-186227D01*
X232028Y-185061D01*
G01X245815Y-178352D02*
X246689Y-177477D01*
X247344Y-176019D01*
X247781Y-173976D01*
X247344Y-172227D01*
X246471Y-171060D01*
X244942Y-170185D01*
X239047D01*
Y-187685D01*
X246252D01*
X247781Y-186519D01*
X248654Y-184768D01*
X249091Y-182727D01*
X248654Y-180685D01*
X247344Y-178935D01*
X245815Y-178352D01*
X239047D01*
G01X255019Y-193518D02*
X268119D01*
G01X274047Y-187685D02*
Y-170185D01*
X284091Y-187685D01*
Y-170185D01*
G01X296569Y-187685D02*
X294822Y-187393D01*
X293294Y-186227D01*
X291984Y-184477D01*
X291110Y-182435D01*
X290674Y-180102D01*
Y-177768D01*
X291110Y-175435D01*
X291984Y-173393D01*
X293294Y-171644D01*
X294822Y-170477D01*
X296569Y-170185D01*
X298315Y-170477D01*
X299844Y-171644D01*
X301154Y-173393D01*
X302028Y-175435D01*
X302464Y-177768D01*
Y-180102D01*
X302028Y-182435D01*
X301154Y-184477D01*
X299844Y-186227D01*
X298315Y-187393D01*
X296569Y-187685D01*
G01X217819Y-232685D02*
Y-215185D01*
X215199Y-218685D01*
G01Y-232685D02*
X220439D01*
G01X234882D02*
X235319Y-228894D01*
X235974Y-225685D01*
X236847Y-222768D01*
X237939Y-219560D01*
X239686Y-215185D01*
X230952D01*
G01X248016Y-229185D02*
X249325Y-231227D01*
X251072Y-232393D01*
X253037Y-232685D01*
X254784Y-232393D01*
X256531Y-230935D01*
X257622Y-229185D01*
X257841Y-227435D01*
X257404Y-225394D01*
X255876Y-223935D01*
X254347Y-223352D01*
X252382D01*
G01X254347D02*
X255657Y-222477D01*
X256749Y-221019D01*
X257186Y-219269D01*
X256749Y-217518D01*
X255657Y-216060D01*
X253692Y-215185D01*
X251727Y-215477D01*
X249762Y-216644D01*
G01X270319Y-215185D02*
X268572Y-215768D01*
X267262Y-217227D01*
X266389Y-218976D01*
X265734Y-221310D01*
X265516Y-223935D01*
X265734Y-226560D01*
X266389Y-228894D01*
X267262Y-230644D01*
X268572Y-232102D01*
X270319Y-232685D01*
X272065Y-232102D01*
X273376Y-230644D01*
X274249Y-228894D01*
X274904Y-226560D01*
X275122Y-223935D01*
X274904Y-221310D01*
X274249Y-218976D01*
X273376Y-217227D01*
X272065Y-215768D01*
X270319Y-215185D01*
G01X287819Y-232685D02*
Y-215185D01*
X285199Y-218685D01*
G01Y-232685D02*
X290439D01*
G01X365784Y-230352D02*
X367531Y-231810D01*
X369496Y-232685D01*
X371242D01*
X372989Y-231810D01*
X374299Y-230352D01*
X374954Y-228310D01*
X374517Y-226269D01*
X373426Y-224518D01*
X371461Y-223352D01*
X368841Y-222768D01*
X367312Y-221602D01*
X366657Y-219560D01*
X367094Y-217518D01*
X368186Y-216060D01*
X369714Y-215185D01*
X371242D01*
X372771Y-215768D01*
X374081Y-217227D01*
G01X382410Y-232685D02*
X387869Y-215185D01*
X393328Y-232685D01*
G01X391362Y-226560D02*
X384375D01*
G01X347410Y-170185D02*
X352869Y-187685D01*
X358328Y-170185D01*
G01X374736Y-187685D02*
X366002D01*
Y-170185D01*
X374736D01*
G01X371242Y-178643D02*
X366002D01*
G01X383502Y-187685D02*
Y-170185D01*
X388961D01*
X390707Y-171060D01*
X391799Y-172227D01*
X392236Y-174560D01*
X391799Y-176894D01*
X390489Y-178352D01*
X388961Y-179227D01*
X383502D01*
G01X388961D02*
X392236Y-187685D01*
G01X405369Y-188268D02*
X404932Y-187977D01*
Y-187393D01*
X405369Y-187102D01*
X405806Y-187393D01*
Y-187977D01*
X405369Y-188268D01*
G01X553573Y-223352D02*
X552699Y-222477D01*
X552044Y-221019D01*
X551607Y-218976D01*
X552044Y-217227D01*
X552917Y-216060D01*
X554446Y-215185D01*
X560341D01*
Y-232685D01*
X553136D01*
X551607Y-231519D01*
X550734Y-229768D01*
X550297Y-227727D01*
X550734Y-225685D01*
X552044Y-223935D01*
X553573Y-223352D01*
X560341D01*
G01X543496Y-232685D02*
Y-215185D01*
X537819Y-229768D01*
X532142Y-215185D01*
Y-232685D01*
G01X525778D02*
X520319Y-215185D01*
X514860Y-232685D01*
G01X516826Y-226560D02*
X523813D01*
G01X507404Y-230352D02*
X505657Y-231810D01*
X503692Y-232685D01*
X501946D01*
X500199Y-231810D01*
X498889Y-230352D01*
X498234Y-228310D01*
X498671Y-226269D01*
X499762Y-224518D01*
X501727Y-223352D01*
X504347Y-222768D01*
X505876Y-221602D01*
X506531Y-219560D01*
X506094Y-217518D01*
X505002Y-216060D01*
X503474Y-215185D01*
X501946D01*
X500417Y-215768D01*
X499107Y-217227D01*
G01X490122Y-232685D02*
Y-215185D01*
G01X481826D02*
X490122Y-225977D01*
G01X480516Y-232685D02*
X486411Y-221019D01*
G01X480952Y-170185D02*
Y-187685D01*
X489686D01*
G01X506749D02*
Y-176019D01*
G01Y-178060D02*
X505876Y-176894D01*
X504565Y-176310D01*
X503037Y-176019D01*
X501509Y-176602D01*
X500199Y-177768D01*
X499325Y-179518D01*
X498889Y-181852D01*
X499325Y-184185D01*
X500199Y-185935D01*
X501509Y-187102D01*
X503037Y-187685D01*
X504565Y-187393D01*
X505876Y-186519D01*
X506749Y-185352D01*
G01X515734Y-192935D02*
X517044Y-193518D01*
X518791Y-192935D01*
X519882Y-191769D01*
X520756Y-190310D01*
X522065Y-185644D01*
X524904Y-176019D01*
G01X517917D02*
X522065Y-185644D01*
G01X534544Y-179810D02*
X541531D01*
X540876Y-177768D01*
X539784Y-176602D01*
X538256Y-176019D01*
X536727Y-176310D01*
X535417Y-177185D01*
X534544Y-179227D01*
X534107Y-180977D01*
Y-182727D01*
X534544Y-184477D01*
X535636Y-186227D01*
X536946Y-187393D01*
X538474Y-187685D01*
X540002Y-187102D01*
X541531Y-185352D01*
G01X552262Y-187685D02*
Y-176019D01*
G01Y-178352D02*
X553354Y-177185D01*
X554446Y-176310D01*
X555974Y-176019D01*
X557065Y-176310D01*
X558376Y-177185D01*
G01X623066Y-187685D02*
Y-170185D01*
X627432D01*
X629179Y-171060D01*
X630489Y-172227D01*
X631581Y-173976D01*
X632454Y-176019D01*
X632672Y-178935D01*
X632454Y-181852D01*
X631581Y-183894D01*
X630489Y-185644D01*
X629179Y-186810D01*
X627432Y-187685D01*
X623066D01*
G01X642094Y-179810D02*
X649081D01*
X648426Y-177768D01*
X647334Y-176602D01*
X645806Y-176019D01*
X644277Y-176310D01*
X642967Y-177185D01*
X642094Y-179227D01*
X641657Y-180977D01*
Y-182727D01*
X642094Y-184477D01*
X643186Y-186227D01*
X644496Y-187393D01*
X646024Y-187685D01*
X647552Y-187102D01*
X649081Y-185352D01*
G01X659594Y-185644D02*
X660686Y-186810D01*
X662214Y-187685D01*
X663524D01*
X664834Y-187102D01*
X665707Y-186227D01*
X666144Y-185061D01*
X665926Y-183310D01*
X665052Y-182435D01*
X661122Y-180685D01*
X660249Y-178643D01*
X660686Y-177185D01*
X661559Y-176310D01*
X662869Y-176019D01*
X664179Y-176310D01*
X665489Y-177185D01*
G01X680369Y-176019D02*
Y-187685D01*
G01Y-171352D02*
X679932Y-171060D01*
Y-170477D01*
X680369Y-170185D01*
X680806Y-170477D01*
Y-171060D01*
X680369Y-171352D01*
G01X694812Y-192060D02*
X696341Y-193227D01*
X698087Y-193518D01*
X699615Y-193227D01*
X700926Y-191769D01*
X701799Y-189727D01*
Y-176019D01*
G01Y-178352D02*
X700926Y-177185D01*
X699615Y-176310D01*
X698087Y-176019D01*
X696341Y-176602D01*
X695249Y-177768D01*
X694375Y-179810D01*
X693939Y-181852D01*
X694157Y-183602D01*
X695031Y-185644D01*
X696341Y-187102D01*
X698087Y-187685D01*
X699397Y-187393D01*
X700926Y-186227D01*
X701799Y-185061D01*
G01X711657Y-187685D02*
Y-176019D01*
G01Y-178935D02*
X712531Y-177477D01*
X713841Y-176310D01*
X715587Y-176019D01*
X717115Y-176310D01*
X718426Y-177477D01*
X719081Y-179518D01*
Y-187685D01*
G01X729594Y-179810D02*
X736581D01*
X735926Y-177768D01*
X734834Y-176602D01*
X733306Y-176019D01*
X731777Y-176310D01*
X730467Y-177185D01*
X729594Y-179227D01*
X729157Y-180977D01*
Y-182727D01*
X729594Y-184477D01*
X730686Y-186227D01*
X731996Y-187393D01*
X733524Y-187685D01*
X735052Y-187102D01*
X736581Y-185352D01*
G01X747312Y-187685D02*
Y-176019D01*
G01Y-178352D02*
X748404Y-177185D01*
X749496Y-176310D01*
X751024Y-176019D01*
X752115Y-176310D01*
X753426Y-177185D01*
G01X664179Y-223935D02*
X668546D01*
Y-229185D01*
X667236Y-230935D01*
X665707Y-232102D01*
X663524Y-232685D01*
X661341Y-232102D01*
X659812Y-230935D01*
X658502Y-229185D01*
X657629Y-227143D01*
X657192Y-224810D01*
Y-222768D01*
X657629Y-221019D01*
X658502Y-218976D01*
X659812Y-217227D01*
X661122Y-216060D01*
X662869Y-215185D01*
X664397D01*
X666144Y-215768D01*
X667454Y-216935D01*
G01X684736Y-232685D02*
X676002D01*
Y-215185D01*
X684736D01*
G01X681242Y-223643D02*
X676002D01*
G01X693502Y-215185D02*
Y-232685D01*
X702236D01*
G01X715369D02*
X713622Y-232393D01*
X712094Y-231227D01*
X710784Y-229477D01*
X709910Y-227435D01*
X709474Y-225102D01*
Y-222768D01*
X709910Y-220435D01*
X710784Y-218393D01*
X712094Y-216644D01*
X713622Y-215477D01*
X715369Y-215185D01*
X717115Y-215477D01*
X718644Y-216644D01*
X719954Y-218393D01*
X720828Y-220435D01*
X721264Y-222768D01*
Y-225102D01*
X720828Y-227435D01*
X719954Y-229477D01*
X718644Y-231227D01*
X717115Y-232393D01*
X715369Y-232685D01*
G01X794069Y-215185D02*
X792322Y-215768D01*
X791012Y-217227D01*
X790139Y-218976D01*
X789484Y-221310D01*
X789266Y-223935D01*
X789484Y-226560D01*
X790139Y-228894D01*
X791012Y-230644D01*
X792322Y-232102D01*
X794069Y-232685D01*
X795815Y-232102D01*
X797126Y-230644D01*
X797999Y-228894D01*
X798654Y-226560D01*
X798872Y-223935D01*
X798654Y-221310D01*
X797999Y-218976D01*
X797126Y-217227D01*
X795815Y-215768D01*
X794069Y-215185D01*
G01X807421Y-225394D02*
X808949Y-223352D01*
X810259Y-222185D01*
X812006Y-221602D01*
X813534Y-222185D01*
X814626Y-223352D01*
X815499Y-225102D01*
X815717Y-227143D01*
X815499Y-228894D01*
X814626Y-230644D01*
X813315Y-232102D01*
X811787Y-232685D01*
X810041Y-232102D01*
X808512Y-230352D01*
X807639Y-227727D01*
X807421Y-224810D01*
X807857Y-221019D01*
X808512Y-218976D01*
X809604Y-216935D01*
X811132Y-215477D01*
X812661Y-215185D01*
X814189Y-215768D01*
X815281Y-217227D01*
G01X825139Y-233268D02*
X832999Y-215185D01*
G01X842421Y-218102D02*
X843731Y-216352D01*
X845259Y-215477D01*
X847006Y-215185D01*
X849189Y-215768D01*
X850717Y-217227D01*
X851154Y-218976D01*
X850936Y-220727D01*
X850062Y-222185D01*
X845696Y-225102D01*
X843731Y-227143D01*
X842421Y-230061D01*
X841984Y-232685D01*
X851154D01*
G01X859921Y-218102D02*
X861231Y-216352D01*
X862759Y-215477D01*
X864506Y-215185D01*
X866689Y-215768D01*
X868217Y-217227D01*
X868654Y-218976D01*
X868436Y-220727D01*
X867562Y-222185D01*
X863196Y-225102D01*
X861231Y-227143D01*
X859921Y-230061D01*
X859484Y-232685D01*
X868654D01*
G01X877639Y-233268D02*
X885499Y-215185D01*
G01X894921Y-218102D02*
X896231Y-216352D01*
X897759Y-215477D01*
X899506Y-215185D01*
X901689Y-215768D01*
X903217Y-217227D01*
X903654Y-218976D01*
X903436Y-220727D01*
X902562Y-222185D01*
X898196Y-225102D01*
X896231Y-227143D01*
X894921Y-230061D01*
X894484Y-232685D01*
X903654D01*
G01X916569Y-215185D02*
X914822Y-215768D01*
X913512Y-217227D01*
X912639Y-218976D01*
X911984Y-221310D01*
X911766Y-223935D01*
X911984Y-226560D01*
X912639Y-228894D01*
X913512Y-230644D01*
X914822Y-232102D01*
X916569Y-232685D01*
X918315Y-232102D01*
X919626Y-230644D01*
X920499Y-228894D01*
X921154Y-226560D01*
X921372Y-223935D01*
X921154Y-221310D01*
X920499Y-218976D01*
X919626Y-217227D01*
X918315Y-215768D01*
X916569Y-215185D01*
G01X934069Y-232685D02*
Y-215185D01*
X931449Y-218685D01*
G01Y-232685D02*
X936689D01*
G01X951132D02*
X951569Y-228894D01*
X952224Y-225685D01*
X953097Y-222768D01*
X954189Y-219560D01*
X955936Y-215185D01*
X947202D01*
G01X841766Y-187685D02*
Y-170185D01*
X846132D01*
X847879Y-171060D01*
X849189Y-172227D01*
X850281Y-173976D01*
X851154Y-176019D01*
X851372Y-178935D01*
X851154Y-181852D01*
X850281Y-183894D01*
X849189Y-185644D01*
X847879Y-186810D01*
X846132Y-187685D01*
X841766D01*
G01X867999D02*
Y-176019D01*
G01Y-178060D02*
X867126Y-176894D01*
X865815Y-176310D01*
X864287Y-176019D01*
X862759Y-176602D01*
X861449Y-177768D01*
X860575Y-179518D01*
X860139Y-181852D01*
X860575Y-184185D01*
X861449Y-185935D01*
X862759Y-187102D01*
X864287Y-187685D01*
X865815Y-187393D01*
X867126Y-186519D01*
X867999Y-185352D01*
G01X881569Y-170185D02*
Y-187685D01*
G01X878512Y-176019D02*
X884626D01*
G01X895794Y-179810D02*
X902781D01*
X902126Y-177768D01*
X901034Y-176602D01*
X899506Y-176019D01*
X897977Y-176310D01*
X896667Y-177185D01*
X895794Y-179227D01*
X895357Y-180977D01*
Y-182727D01*
X895794Y-184477D01*
X896886Y-186227D01*
X898196Y-187393D01*
X899724Y-187685D01*
X901252Y-187102D01*
X902781Y-185352D01*
G54D29*
X297578Y81023D03*
Y78071D03*
Y75118D03*
Y98740D03*
Y95787D03*
Y92835D03*
Y89882D03*
Y86929D03*
Y83976D03*
X322106Y81023D03*
Y78071D03*
Y75118D03*
X308208Y81023D03*
Y78071D03*
Y75118D03*
X322106Y98740D03*
Y95787D03*
Y92835D03*
Y89882D03*
Y86929D03*
Y83976D03*
X308208Y98740D03*
Y95787D03*
Y92835D03*
Y89882D03*
Y86929D03*
Y83976D03*
X332736Y81023D03*
Y78071D03*
Y75118D03*
Y98740D03*
Y95787D03*
Y92835D03*
Y89882D03*
Y86929D03*
Y83976D03*
G54D38*
X313000Y46300D03*
G54D39*
X316624Y56703D03*
X319400Y141500D03*
X325624Y56703D03*
X328400Y141500D03*
X349900Y29400D03*
X358900D03*
M02*
